# BASEBOARD_FAB2 (Tioga Pass) — schematic netlist excerpt (pin names and nets, part order shuffled) for the footprints in the layout excerpt that follows; sources: Cadence DE-HDL packaged netlist, KiCad conversion of Wiwynn_Tioga_Pass_MB.brd

C6F6  CAP  10UF 4V 20% X6S  pkg 0603LF  page 231 : A = PVPP_ABC ; B = GND
C3G6  CAP_A  47UF 4V 20% X5R  pkg 0603V  page 225 : A = PVDDQ_GHJ ; B = GND

(kicad_pcb
	(version 20260206)
	(generator "pcbnew")
	(generator_version "10.0")
	(general
		(thickness 1.6)
		(legacy_teardrops no)
	)
	(paper "A4")
	(title_block
		(title "Wiwynn_Tioga_Pass_MB.brd")
		(comment 1 "Tioga Pass / footprints 2290-2291 of 4770")
	)
	(layers
		(0 "F.Cu" signal "TOP")
		(4 "In1.Cu" signal "L2GND")
		(6 "In2.Cu" signal "L3")
		(8 "In3.Cu" signal "L4GND")
		(10 "In4.Cu" signal "L5")
		(12 "In5.Cu" signal "L6GND")
		(14 "In6.Cu" signal "L7VCC")
		(16 "In7.Cu" signal "L8VCC")
		(18 "In8.Cu" signal "L9GND")
		(20 "In9.Cu" signal "L10")
		(22 "In10.Cu" signal "L11GND")
		(24 "In11.Cu" signal "L12")
		(26 "In12.Cu" signal "L13GND")
		(2 "B.Cu" signal "BOTTOM")
		(9 "F.Adhes" user "F.Adhesive")
		(11 "B.Adhes" user "B.Adhesive")
		(13 "F.Paste" user "Package Geometry/Pastemask Top")
		(15 "B.Paste" user "Package Geometry/Pastemask Bottom")
		(5 "F.SilkS" user "Ref Des/Silkscreen Top")
		(7 "B.SilkS" user "Ref Des/Silkscreen Bottom")
		(1 "F.Mask" user "Board Geometry/Soldermask Top")
		(3 "B.Mask" user "Board Geometry/Soldermask Bottom")
		(17 "Dwgs.User" user "User.Drawings")
		(19 "Cmts.User" user "User.Comments")
		(21 "Eco1.User" user "User.Eco1")
		(23 "Eco2.User" user "User.Eco2")
		(25 "Edge.Cuts" user "Board Geometry/Outline")
		(27 "Margin" user)
		(31 "F.CrtYd" user "Package Geometry/Place Bound Top")
		(29 "B.CrtYd" user "Package Geometry/Place Bound Bottom")
		(35 "F.Fab" user "Ref Des/Assembly Top")
		(33 "B.Fab" user "Ref Des/Assembly Bottom")
	)
	(footprint ""
		(layer "F.Cu")
		(at 320.194432 -22.740112 90)
		(property "Reference" "C6F6"
			(at 0 0 90)
			(layer "F.SilkS")
			(hide yes)
			(effects
				(font
					(size 1.27 1.27)
				)
			)
		)
		(property "Value" ""
			(at 0 0 90)
			(layer "F.Fab")
			(effects
				(font
					(size 1.27 1.27)
				)
			)
		)
		(duplicate_pad_numbers_are_jumpers no)
		(fp_poly
			(pts
				(xy -0.4953 -0.2032) (xy 0.4953 -0.2032) (xy 0.4953 1.6002) (xy -0.4953 1.6002)
			)
			(stroke
				(width 0)
				(type default)
			)
			(fill no)
			(layer "F.CrtYd")
		)
		(fp_line
			(start 0.4953 -0.2032)
			(end 0.4953 1.6002)
			(stroke
				(width 0.1)
				(type default)
			)
			(layer "F.Fab")
		)
		(fp_line
			(start -0.4953 -0.2032)
			(end 0.4953 -0.2032)
			(stroke
				(width 0.1)
				(type default)
			)
			(layer "F.Fab")
		)
		(fp_line
			(start 0.4953 1.6002)
			(end -0.4953 1.6002)
			(stroke
				(width 0.1)
				(type default)
			)
			(layer "F.Fab")
		)
		(fp_line
			(start -0.4953 1.6002)
			(end -0.4953 -0.2032)
			(stroke
				(width 0.1)
				(type default)
			)
			(layer "F.Fab")
		)
		(pad "1" smd rect
			(at 0 0 90)
			(size 0.762 0.889)
			(layers "F.Cu" "F.Mask" "F.Paste")
			(net "PVPP_ABC")
		)
		(pad "2" smd rect
			(at 0 1.397 90)
			(size 0.762 0.889)
			(layers "F.Cu" "F.Mask" "F.Paste")
			(net "GND")
		)
		(zone
			(layer "F.Cu")
			(hatch none 0.5)
			(connect_pads
				(clearance 0)
			)
			(min_thickness 0.25)
			(keepout
				(tracks not_allowed)
				(vias allowed)
				(pads allowed)
				(copperpour not_allowed)
				(footprints allowed)
			)
			(placement
				(enabled no)
				(sheetname "")
			)
			(fill
				(thermal_gap 0.5)
				(thermal_bridge_width 0.5)
				(island_removal_mode 0)
			)
			(polygon
				(pts
					(xy 320.638932 -22.359112) (xy 320.638932 -23.121112) (xy 321.146932 -23.121112) (xy 321.146932 -22.359112)
				)
			)
		)
	)
	(footprint ""
		(layer "F.Cu")
		(at 111.000032 -3.3528 90)
		(property "Reference" "C3G6"
			(at 1.848866 0.752348 90)
			(unlocked yes)
			(layer "F.SilkS")
			(effects
				(font
					(size 1.27 0.9652)
					(thickness 0.1524)
				)
			)
		)
		(property "Value" ""
			(at 0 0 90)
			(layer "F.Fab")
			(effects
				(font
					(size 1.27 1.27)
				)
			)
		)
		(duplicate_pad_numbers_are_jumpers no)
		(fp_rect
			(start -0.500126 1.598422)
			(end 0.500126 -0.201422)
			(stroke
				(width 0)
				(type default)
			)
			(fill no)
			(layer "F.CrtYd")
		)
		(fp_line
			(start 0.500126 -0.201422)
			(end 0.500126 1.598422)
			(stroke
				(width 0.1)
				(type default)
			)
			(layer "F.Fab")
		)
		(fp_line
			(start -0.500126 -0.201422)
			(end 0.500126 -0.201422)
			(stroke
				(width 0.1)
				(type default)
			)
			(layer "F.Fab")
		)
		(fp_line
			(start 0.500126 1.598422)
			(end -0.500126 1.598422)
			(stroke
				(width 0.1)
				(type default)
			)
			(layer "F.Fab")
		)
		(fp_line
			(start -0.500126 1.598422)
			(end -0.500126 -0.201422)
			(stroke
				(width 0.1)
				(type default)
			)
			(layer "F.Fab")
		)
		(pad "1" smd rect
			(at 0 0)
			(size 0.889 0.9906)
			(layers "F.Cu" "F.Mask" "F.Paste")
			(net "PVDDQ_GHJ")
		)
		(pad "2" smd rect
			(at 0 1.397)
			(size 0.889 0.9906)
			(layers "F.Cu" "F.Mask" "F.Paste")
			(net "GND")
		)
		(zone
			(layer "F.Cu")
			(hatch none 0.5)
			(connect_pads
				(clearance 0)
			)
			(min_thickness 0.25)
			(keepout
				(tracks allowed)
				(vias not_allowed)
				(pads allowed)
				(copperpour not_allowed)
				(footprints allowed)
			)
			(placement
				(enabled no)
				(sheetname "")
			)
			(fill
				(thermal_gap 0.5)
				(thermal_bridge_width 0.5)
				(island_removal_mode 0)
			)
			(polygon
				(pts
					(xy 111.952532 -2.8575) (xy 111.952532 -3.8481) (xy 111.444532 -3.8481) (xy 111.444532 -2.8575)
				)
			)
		)
		(zone
			(layer "F.Cu")
			(hatch none 0.5)
			(connect_pads
				(clearance 0)
			)
			(min_thickness 0.25)
			(keepout
				(tracks not_allowed)
				(vias allowed)
				(pads allowed)
				(copperpour not_allowed)
				(footprints allowed)
			)
			(placement
				(enabled no)
				(sheetname "")
			)
			(fill
				(thermal_gap 0.5)
				(thermal_bridge_width 0.5)
				(island_removal_mode 0)
			)
			(polygon
				(pts
					(xy 111.952532 -2.8575) (xy 111.952532 -3.8481) (xy 111.444532 -3.8481) (xy 111.444532 -2.8575)
				)
			)
		)
	)
)
